(kicad_pcb
	(version 20260206)
	(generator "pcbnew")
	(generator_version "10.0")
	(general
		(thickness 1.6)
		(legacy_teardrops no)
	)
	(paper "A4")
	(title_block
		(title "04192023_DAF0TMB3IC0_F0TG_MB_C_brd_V02_OCP.brd")
		(comment 1 "Grand Teton / footprints 2885-2889 of 8354")
	)
	(layers
		(0 "F.Cu" signal "TOP")
		(4 "In1.Cu" signal "GND")
		(6 "In2.Cu" signal "IN1")
		(8 "In3.Cu" signal "GND1")
		(10 "In4.Cu" signal "IN2")
		(12 "In5.Cu" signal "GND2")
		(14 "In6.Cu" signal "IN3")
		(16 "In7.Cu" signal "GND3")
		(18 "In8.Cu" signal "VCC")
		(20 "In9.Cu" signal "VCC1")
		(22 "In10.Cu" signal "GND4")
		(24 "In11.Cu" signal "IN4")
		(26 "In12.Cu" signal "GND5")
		(28 "In13.Cu" signal "IN5")
		(30 "In14.Cu" signal "GND6")
		(32 "In15.Cu" signal "IN6")
		(34 "In16.Cu" signal "GND7")
		(2 "B.Cu" signal "BOTTOM")
		(9 "F.Adhes" user "F.Adhesive")
		(11 "B.Adhes" user "B.Adhesive")
		(13 "F.Paste" user "Package Geometry/Pastemask Top")
		(15 "B.Paste" user "Package Geometry/Pastemask Bottom")
		(5 "F.SilkS" user "Ref Des/Silkscreen Top")
		(7 "B.SilkS" user "Ref Des/Silkscreen Bottom")
		(1 "F.Mask" user "Board Geometry/Soldermask Top")
		(3 "B.Mask" user "Board Geometry/Soldermask Bottom")
		(17 "Dwgs.User" user "User.Drawings")
		(19 "Cmts.User" user "User.Comments")
		(21 "Eco1.User" user "User.Eco1")
		(23 "Eco2.User" user "User.Eco2")
		(25 "Edge.Cuts" user "Board Geometry/Outline")
		(27 "Margin" user)
		(31 "F.CrtYd" user "Package Geometry/Place Bound Top")
		(29 "B.CrtYd" user "Package Geometry/Place Bound Bottom")
		(35 "F.Fab" user "Ref Des/Assembly Top")
		(33 "B.Fab" user "Ref Des/Assembly Bottom")
	)
	(footprint ""
		(layer "F.Cu")
		(at 11.176 -39.1668)
		(property "Reference" "H28"
			(at -1.16586 -4.917948 0)
			(unlocked yes)
			(layer "F.SilkS")
			(effects
				(font
					(size 0.7874 0.5842)
					(thickness 0.1524)
				)
				(justify left)
			)
		)
		(property "Value" ""
			(at 0 0 0)
			(layer "F.Fab")
			(effects
				(font
					(size 1.27 1.27)
				)
			)
		)
		(duplicate_pad_numbers_are_jumpers no)
		(fp_circle
			(center 0 0)
			(end 2.4003 0)
			(stroke
				(width 0.1524)
				(type default)
			)
			(fill no)
			(layer "F.SilkS")
		)
		(fp_arc
			(start -6.391402 1.610868)
			(mid -0.81161 -6.541116)
			(end 6.5913 0)
			(stroke
				(width 0.1524)
				(type default)
			)
			(layer "B.SilkS")
		)
		(fp_arc
			(start 6.5913 0)
			(mid 2.749338 5.990524)
			(end -4.29768 4.99745)
			(stroke
				(width 0.1524)
				(type default)
			)
			(layer "B.SilkS")
		)
		(fp_circle
			(center 0 0)
			(end 6.5913 0)
			(stroke
				(width 0.1)
				(type default)
			)
			(fill no)
			(layer "B.Fab")
		)
		(fp_circle
			(center 0 0)
			(end 2.4003 0)
			(stroke
				(width 0.1)
				(type default)
			)
			(fill no)
			(layer "F.Fab")
		)
		(pad "" np_thru_hole circle
			(at 0 0)
			(size 3.175 3.175)
			(drill 3.175)
			(layers "*.Cu" "*.Mask")
			(clearance 0.381)
			(thermal_gap 0.381)
		)
		(zone
			(layers "F.Cu" "B.Cu" "In1.Cu" "In2.Cu" "In3.Cu" "In4.Cu" "In5.Cu" "In6.Cu"
				"In7.Cu" "In8.Cu" "In9.Cu" "In10.Cu" "In11.Cu" "In12.Cu" "In13.Cu" "In14.Cu"
				"In15.Cu" "In16.Cu"
			)
			(hatch none 0.5)
			(connect_pads
				(clearance 0)
			)
			(min_thickness 0.25)
			(keepout
				(tracks not_allowed)
				(vias allowed)
				(pads allowed)
				(copperpour not_allowed)
				(footprints allowed)
			)
			(placement
				(enabled no)
				(sheetname "")
			)
			(fill
				(thermal_gap 0.5)
				(thermal_bridge_width 0.5)
				(island_removal_mode 0)
			)
			(polygon
				(pts
					(arc
						(start 13.2715 -39.1668)
						(mid 9.0805 -39.1668)
						(end 13.2715 -39.1668)
					)
				)
			)
		)
	)
	(footprint ""
		(layer "F.Cu")
		(at 429.136302 -436.164736 -90)
		(property "Reference" "R2832"
			(at 0 0 270)
			(layer "F.SilkS")
			(hide yes)
			(effects
				(font
					(size 1.27 1.27)
				)
			)
		)
		(property "Value" ""
			(at 0 0 270)
			(layer "F.Fab")
			(effects
				(font
					(size 1.27 1.27)
				)
			)
		)
		(duplicate_pad_numbers_are_jumpers no)
		(fp_line
			(start -0.7874 0.4064)
			(end -0.7874 -0.4064)
			(stroke
				(width 0.1524)
				(type default)
			)
			(layer "F.SilkS")
		)
		(fp_line
			(start 0.7874 0.4064)
			(end -0.7874 0.4064)
			(stroke
				(width 0.1524)
				(type default)
			)
			(layer "F.SilkS")
		)
		(fp_line
			(start -0.7874 -0.4064)
			(end 0.7874 -0.4064)
			(stroke
				(width 0.1524)
				(type default)
			)
			(layer "F.SilkS")
		)
		(fp_line
			(start 0.7874 -0.4064)
			(end 0.7874 0.4064)
			(stroke
				(width 0.1524)
				(type default)
			)
			(layer "F.SilkS")
		)
		(fp_line
			(start -0.67945 0.3048)
			(end -0.67945 -0.305054)
			(stroke
				(width 0.1)
				(type default)
			)
			(layer "F.Fab")
		)
		(fp_line
			(start -0.12065 0.3048)
			(end -0.67945 0.3048)
			(stroke
				(width 0.1)
				(type default)
			)
			(layer "F.Fab")
		)
		(fp_line
			(start 0.120396 0.3048)
			(end 0.120396 0.2794)
			(stroke
				(width 0.1)
				(type default)
			)
			(layer "F.Fab")
		)
		(fp_line
			(start 0.67945 0.3048)
			(end 0.120396 0.3048)
			(stroke
				(width 0.1)
				(type default)
			)
			(layer "F.Fab")
		)
		(fp_line
			(start -0.12065 0.2794)
			(end -0.12065 0.3048)
			(stroke
				(width 0.1)
				(type default)
			)
			(layer "F.Fab")
		)
		(fp_line
			(start 0.120396 0.2794)
			(end -0.12065 0.2794)
			(stroke
				(width 0.1)
				(type default)
			)
			(layer "F.Fab")
		)
		(fp_line
			(start -0.12065 -0.2794)
			(end 0.12065 -0.2794)
			(stroke
				(width 0.1)
				(type default)
			)
			(layer "F.Fab")
		)
		(fp_line
			(start 0.12065 -0.2794)
			(end 0.12065 -0.3048)
			(stroke
				(width 0.1)
				(type default)
			)
			(layer "F.Fab")
		)
		(fp_line
			(start 0.12065 -0.3048)
			(end 0.67945 -0.3048)
			(stroke
				(width 0.1)
				(type default)
			)
			(layer "F.Fab")
		)
		(fp_line
			(start 0.67945 -0.3048)
			(end 0.67945 0.3048)
			(stroke
				(width 0.1)
				(type default)
			)
			(layer "F.Fab")
		)
		(fp_line
			(start -0.67945 -0.305054)
			(end -0.12065 -0.305054)
			(stroke
				(width 0.1)
				(type default)
			)
			(layer "F.Fab")
		)
		(fp_line
			(start -0.12065 -0.305054)
			(end -0.12065 -0.2794)
			(stroke
				(width 0.1)
				(type default)
			)
			(layer "F.Fab")
		)
		(pad "1" smd circle
			(at -0.40005 0 270)
			(size 0 0)
			(layers "F.Cu" "F.Mask" "F.Paste")
			(net "P3V3_AUX")
		)
		(pad "2" smd circle
			(at 0.40005 0 270)
			(size 0 0)
			(layers "F.Cu" "F.Mask" "F.Paste")
			(net "FM_SWB_BIC_READY_N")
		)
	)
	(footprint ""
		(layer "F.Cu")
		(at 44.069 -434.594 180)
		(property "Reference" "R3507"
			(at 0 0 180)
			(layer "F.SilkS")
			(hide yes)
			(effects
				(font
					(size 1.27 1.27)
				)
			)
		)
		(property "Value" ""
			(at 0 0 180)
			(layer "F.Fab")
			(effects
				(font
					(size 1.27 1.27)
				)
			)
		)
		(duplicate_pad_numbers_are_jumpers no)
		(fp_line
			(start 0.7874 0.4064)
			(end -0.7874 0.4064)
			(stroke
				(width 0.1524)
				(type default)
			)
			(layer "F.SilkS")
		)
		(fp_line
			(start 0.7874 -0.4064)
			(end 0.7874 0.4064)
			(stroke
				(width 0.1524)
				(type default)
			)
			(layer "F.SilkS")
		)
		(fp_line
			(start -0.7874 0.4064)
			(end -0.7874 -0.4064)
			(stroke
				(width 0.1524)
				(type default)
			)
			(layer "F.SilkS")
		)
		(fp_line
			(start -0.7874 -0.4064)
			(end 0.7874 -0.4064)
			(stroke
				(width 0.1524)
				(type default)
			)
			(layer "F.SilkS")
		)
		(fp_line
			(start 0.67945 0.3048)
			(end 0.120396 0.3048)
			(stroke
				(width 0.1)
				(type default)
			)
			(layer "F.Fab")
		)
		(fp_line
			(start 0.67945 -0.3048)
			(end 0.67945 0.3048)
			(stroke
				(width 0.1)
				(type default)
			)
			(layer "F.Fab")
		)
		(fp_line
			(start 0.12065 -0.2794)
			(end 0.12065 -0.3048)
			(stroke
				(width 0.1)
				(type default)
			)
			(layer "F.Fab")
		)
		(fp_line
			(start 0.12065 -0.3048)
			(end 0.67945 -0.3048)
			(stroke
				(width 0.1)
				(type default)
			)
			(layer "F.Fab")
		)
		(fp_line
			(start 0.120396 0.3048)
			(end 0.120396 0.2794)
			(stroke
				(width 0.1)
				(type default)
			)
			(layer "F.Fab")
		)
		(fp_line
			(start 0.120396 0.2794)
			(end -0.12065 0.2794)
			(stroke
				(width 0.1)
				(type default)
			)
			(layer "F.Fab")
		)
		(fp_line
			(start -0.12065 0.3048)
			(end -0.67945 0.3048)
			(stroke
				(width 0.1)
				(type default)
			)
			(layer "F.Fab")
		)
		(fp_line
			(start -0.12065 0.2794)
			(end -0.12065 0.3048)
			(stroke
				(width 0.1)
				(type default)
			)
			(layer "F.Fab")
		)
		(fp_line
			(start -0.12065 -0.2794)
			(end 0.12065 -0.2794)
			(stroke
				(width 0.1)
				(type default)
			)
			(layer "F.Fab")
		)
		(fp_line
			(start -0.12065 -0.305054)
			(end -0.12065 -0.2794)
			(stroke
				(width 0.1)
				(type default)
			)
			(layer "F.Fab")
		)
		(fp_line
			(start -0.67945 0.3048)
			(end -0.67945 -0.305054)
			(stroke
				(width 0.1)
				(type default)
			)
			(layer "F.Fab")
		)
		(fp_line
			(start -0.67945 -0.305054)
			(end -0.12065 -0.305054)
			(stroke
				(width 0.1)
				(type default)
			)
			(layer "F.Fab")
		)
		(pad "1" smd circle
			(at -0.40005 0 180)
			(size 0 0)
			(layers "F.Cu" "F.Mask" "F.Paste")
			(net "GPU_FPGA_RST_R_N")
		)
		(pad "2" smd circle
			(at 0.40005 0 180)
			(size 0 0)
			(layers "F.Cu" "F.Mask" "F.Paste")
			(net "GND")
		)
	)
	(footprint ""
		(layer "F.Cu")
		(at 323.018404 -334.986376 -90)
		(property "Reference" "PC82_C1P0_2"
			(at 0 0 270)
			(layer "F.SilkS")
			(hide yes)
			(effects
				(font
					(size 1.27 1.27)
				)
			)
		)
		(property "Value" ""
			(at 0 0 270)
			(layer "F.Fab")
			(effects
				(font
					(size 1.27 1.27)
				)
			)
		)
		(duplicate_pad_numbers_are_jumpers no)
		(fp_line
			(start -0.7874 0.4064)
			(end -0.7874 -0.4064)
			(stroke
				(width 0.1524)
				(type default)
			)
			(layer "F.SilkS")
		)
		(fp_line
			(start 0.7874 0.4064)
			(end -0.7874 0.4064)
			(stroke
				(width 0.1524)
				(type default)
			)
			(layer "F.SilkS")
		)
		(fp_line
			(start -0.7874 -0.4064)
			(end 0.7874 -0.4064)
			(stroke
				(width 0.1524)
				(type default)
			)
			(layer "F.SilkS")
		)
		(fp_line
			(start 0.7874 -0.4064)
			(end 0.7874 0.4064)
			(stroke
				(width 0.1524)
				(type default)
			)
			(layer "F.SilkS")
		)
		(fp_line
			(start -0.67945 0.3048)
			(end -0.67945 -0.305054)
			(stroke
				(width 0.1)
				(type default)
			)
			(layer "F.Fab")
		)
		(fp_line
			(start -0.12065 0.3048)
			(end -0.67945 0.3048)
			(stroke
				(width 0.1)
				(type default)
			)
			(layer "F.Fab")
		)
		(fp_line
			(start 0.120396 0.3048)
			(end 0.120396 0.2794)
			(stroke
				(width 0.1)
				(type default)
			)
			(layer "F.Fab")
		)
		(fp_line
			(start 0.67945 0.3048)
			(end 0.120396 0.3048)
			(stroke
				(width 0.1)
				(type default)
			)
			(layer "F.Fab")
		)
		(fp_line
			(start -0.12065 0.2794)
			(end -0.12065 0.3048)
			(stroke
				(width 0.1)
				(type default)
			)
			(layer "F.Fab")
		)
		(fp_line
			(start 0.120396 0.2794)
			(end -0.12065 0.2794)
			(stroke
				(width 0.1)
				(type default)
			)
			(layer "F.Fab")
		)
		(fp_line
			(start -0.12065 -0.2794)
			(end 0.12065 -0.2794)
			(stroke
				(width 0.1)
				(type default)
			)
			(layer "F.Fab")
		)
		(fp_line
			(start 0.12065 -0.2794)
			(end 0.12065 -0.3048)
			(stroke
				(width 0.1)
				(type default)
			)
			(layer "F.Fab")
		)
		(fp_line
			(start 0.12065 -0.3048)
			(end 0.67945 -0.3048)
			(stroke
				(width 0.1)
				(type default)
			)
			(layer "F.Fab")
		)
		(fp_line
			(start 0.67945 -0.3048)
			(end 0.67945 0.3048)
			(stroke
				(width 0.1)
				(type default)
			)
			(layer "F.Fab")
		)
		(fp_line
			(start -0.67945 -0.305054)
			(end -0.12065 -0.305054)
			(stroke
				(width 0.1)
				(type default)
			)
			(layer "F.Fab")
		)
		(fp_line
			(start -0.12065 -0.305054)
			(end -0.12065 -0.2794)
			(stroke
				(width 0.1)
				(type default)
			)
			(layer "F.Fab")
		)
		(pad "1" smd circle
			(at -0.40005 0 270)
			(size 0 0)
			(layers "F.Cu" "F.Mask" "F.Paste")
			(net "PVDDCR_CPU1_P0_PVCC")
		)
		(pad "2" smd circle
			(at 0.40005 0 270)
			(size 0 0)
			(layers "F.Cu" "F.Mask" "F.Paste")
			(net "GND")
		)
	)
	(footprint ""
		(layer "F.Cu")
		(at 87.122254 -334.978502)
		(property "Reference" "PU35"
			(at -3.048254 -8.529828 0)
			(unlocked yes)
			(layer "F.SilkS")
			(effects
				(font
					(size 0.7874 0.5842)
					(thickness 0.1524)
				)
				(justify left)
			)
		)
		(property "Value" ""
			(at 0 0 0)
			(layer "F.Fab")
			(effects
				(font
					(size 1.27 1.27)
				)
			)
		)
		(duplicate_pad_numbers_are_jumpers no)
		(fp_line
			(start -2.500122 -2.999994)
			(end -2.24409 -2.999994)
			(stroke
				(width 0.1524)
				(type default)
			)
			(layer "F.SilkS")
		)
		(fp_line
			(start -2.500122 -2.529078)
			(end -2.500122 -2.999994)
			(stroke
				(width 0.1524)
				(type default)
			)
			(layer "F.SilkS")
		)
		(fp_line
			(start -2.500122 0.6604)
			(end -2.500122 0.229108)
			(stroke
				(width 0.1524)
				(type default)
			)
			(layer "F.SilkS")
		)
		(fp_line
			(start -2.500122 2.999994)
			(end -2.500122 2.339594)
			(stroke
				(width 0.1524)
				(type default)
			)
			(layer "F.SilkS")
		)
		(fp_line
			(start -2.2987 2.999994)
			(end -2.500122 2.999994)
			(stroke
				(width 0.1524)
				(type default)
			)
			(layer "F.SilkS")
		)
		(fp_line
			(start 2.31394 -2.999994)
			(end 2.500122 -2.999994)
			(stroke
				(width 0.1524)
				(type default)
			)
			(layer "F.SilkS")
		)
		(fp_line
			(start 2.500122 -2.999994)
			(end 2.500122 -2.44348)
			(stroke
				(width 0.1524)
				(type default)
			)
			(layer "F.SilkS")
		)
		(fp_line
			(start 2.500122 2.339594)
			(end 2.500122 2.999994)
			(stroke
				(width 0.1524)
				(type default)
			)
			(layer "F.SilkS")
		)
		(fp_line
			(start 2.500122 2.999994)
			(end 2.2987 2.999994)
			(stroke
				(width 0.1524)
				(type default)
			)
			(layer "F.SilkS")
		)
		(fp_poly
			(pts
				(xy -2.737612 -2.387092) (xy -3.410966 -2.611628) (xy -2.962148 -3.0607)
			)
			(stroke
				(width 0)
				(type default)
			)
			(fill yes)
			(layer "F.SilkS")
		)
		(fp_line
			(start -2.500122 -2.999994)
			(end 2.500122 -2.999994)
			(stroke
				(width 0.1)
				(type default)
			)
			(layer "F.Fab")
		)
		(fp_line
			(start -2.500122 2.999994)
			(end -2.500122 -2.999994)
			(stroke
				(width 0.1)
				(type default)
			)
			(layer "F.Fab")
		)
		(fp_line
			(start 2.500122 -2.999994)
			(end 2.500122 2.999994)
			(stroke
				(width 0.1)
				(type default)
			)
			(layer "F.Fab")
		)
		(fp_line
			(start 2.500122 2.999994)
			(end -2.500122 2.999994)
			(stroke
				(width 0.1)
				(type default)
			)
			(layer "F.Fab")
		)
		(fp_poly
			(pts
				(xy -4.218432 -2.783078) (xy -4.218432 -1.767078) (xy -3.202432 -2.275078)
			)
			(stroke
				(width 0)
				(type default)
			)
			(fill yes)
			(layer "F.Fab")
		)
		(pad "1" smd rect
			(at -2.400046 -2.275078 90)
			(size 0.2286 0.6096)
			(layers "F.Cu" "F.Mask" "F.Paste")
			(net "PVDDCR_CPU1_P1_VOS1")
		)
		(pad "2" smd rect
			(at -2.400046 -1.82499 90)
			(size 0.2286 0.6096)
			(layers "F.Cu" "F.Mask" "F.Paste")
			(net "GND")
		)
		(pad "3" smd rect
			(at -2.400046 -1.374902 90)
			(size 0.2286 0.6096)
			(layers "F.Cu" "F.Mask" "F.Paste")
			(net "PVDDCR_CPU1_P1_VCC1")
		)
		(pad "4" smd rect
			(at -2.400046 -0.925068 90)
			(size 0.2286 0.6096)
			(layers "F.Cu" "F.Mask" "F.Paste")
			(net "PVDDCR_CPU1_P1_PVCC")
		)
		(pad "5" smd rect
			(at -2.400046 -0.47498 90)
			(size 0.2286 0.6096)
			(layers "F.Cu" "F.Mask" "F.Paste")
			(net "GND")
		)
		(pad "6" smd rect
			(at -2.400046 -0.024892 90)
			(size 0.2286 0.6096)
			(layers "F.Cu" "F.Mask" "F.Paste")
			(net "NC_PVDDCR_CPU1_P1_GL1_1")
		)
		(pad "7_9-20_24" smd circle
			(at 0 1.150112 90)
			(size 0 0)
			(layers "F.Cu" "F.Mask" "F.Paste")
			(net "GND")
		)
		(pad "10_19" smd rect
			(at 0 2.899918 90)
			(size 0.6096 4.318)
			(layers "F.Cu" "F.Mask" "F.Paste")
			(net "SW_PVDDCR_CPU1_P1_SW1")
		)
		(pad "25_29" smd rect
			(at 1.549908 -1.279906 270)
			(size 2.0574 2.3114)
			(layers "F.Cu" "F.Mask" "F.Paste")
			(net "SW_P12V_AUX_PVDDCR_CPU1_P1_FLT")
		)
		(pad "30" smd rect
			(at 2.05994 -2.899918)
			(size 0.2286 0.6096)
			(layers "F.Cu" "F.Mask" "F.Paste")
			(net "SW_P12V_AUX_PVDDCR_CPU1_P1_FLT")
		)
		(pad "31" smd rect
			(at 1.610106 -2.899918)
			(size 0.2286 0.6096)
			(layers "F.Cu" "F.Mask" "F.Paste")
			(net "NC_PVDDCR_CPU1_P1_DNC1")
		)
		(pad "32" smd rect
			(at 1.160018 -2.899918)
			(size 0.2286 0.6096)
			(layers "F.Cu" "F.Mask" "F.Paste")
			(net "SW_PVDDCR_CPU1_P1_BOOTR1")
		)
		(pad "33" smd rect
			(at 0.70993 -2.899918)
			(size 0.2286 0.6096)
			(layers "F.Cu" "F.Mask" "F.Paste")
			(net "SW_PVDDCR_CPU1_P1_BOOT1")
		)
		(pad "34" smd rect
			(at 0.260096 -2.899918)
			(size 0.2286 0.6096)
			(layers "F.Cu" "F.Mask" "F.Paste")
			(net "PVDDCR_CPU1_P1_PWM1")
		)
		(pad "35" smd rect
			(at -0.189992 -2.899918)
			(size 0.2286 0.6096)
			(layers "F.Cu" "F.Mask" "F.Paste")
			(net "PVDDCR_CPU1_P1_VCC1")
		)
		(pad "36" smd rect
			(at -0.64008 -2.899918)
			(size 0.2286 0.6096)
			(layers "F.Cu" "F.Mask" "F.Paste")
			(net "PVDDCR_CPU1_P1_TEMP0")
		)
		(pad "37" smd rect
			(at -1.089914 -2.899918)
			(size 0.2286 0.6096)
			(layers "F.Cu" "F.Mask" "F.Paste")
			(net "PVDDCR_CPU1_P1_LSET1")
		)
		(pad "38" smd rect
			(at -1.540002 -2.899918)
			(size 0.2286 0.6096)
			(layers "F.Cu" "F.Mask" "F.Paste")
			(net "PVDDCR_CPU1_P1_IMON1")
		)
		(pad "39" smd rect
			(at -1.99009 -2.899918)
			(size 0.2286 0.6096)
			(layers "F.Cu" "F.Mask" "F.Paste")
			(net "PVDDCR_CPU1_P1_VCCS")
		)
		(pad "40" smd rect
			(at -0.87503 -1.27508)
			(size 1.7526 1.9558)
			(layers "F.Cu" "F.Mask" "F.Paste")
			(net "GND")
		)
		(pad "41" smd rect
			(at -1.525016 0.249936 270)
			(size 0.3048 0.4572)
			(layers "F.Cu" "F.Mask" "F.Paste")
			(net "NC_PVDDCR_CPU1_P1_GL2_1")
		)
		(zone
			(layer "F.Cu")
			(hatch none 0.5)
			(connect_pads
				(clearance 0)
			)
			(min_thickness 0.25)
			(keepout
				(tracks not_allowed)
				(vias allowed)
				(pads allowed)
				(copperpour not_allowed)
				(footprints allowed)
			)
			(placement
				(enabled no)
				(sheetname "")
			)
			(fill
				(thermal_gap 0.5)
				(thermal_bridge_width 0.5)
				(island_removal_mode 0)
			)
			(polygon
				(pts
					(xy 84.622132 -332.40599) (xy 84.622132 -332.727808) (xy 89.622376 -332.727808) (xy 89.622376 -332.394306)
					(xy 89.332054 -332.394306) (xy 89.332054 -332.434184) (xy 84.912454 -332.434184) (xy 84.912454 -332.40599)
				)
			)
		)
		(zone
			(layer "F.Cu")
			(hatch none 0.5)
			(connect_pads
				(clearance 0)
			)
			(min_thickness 0.25)
			(keepout
				(tracks not_allowed)
				(vias allowed)
				(pads allowed)
				(copperpour not_allowed)
				(footprints allowed)
			)
			(placement
				(enabled no)
				(sheetname "")
			)
			(fill
				(thermal_gap 0.5)
				(thermal_bridge_width 0.5)
				(island_removal_mode 0)
			)
			(polygon
				(pts
					(xy 87.174324 -335.224882) (xy 87.174324 -337.282282) (xy 85.320124 -337.282282) (xy 85.320124 -337.041236)
					(xy 85.077808 -337.041236) (xy 85.077808 -337.52282) (xy 88.87587 -337.52282) (xy 88.87587 -337.337908)
					(xy 87.465662 -337.337908) (xy 87.465662 -335.178908) (xy 89.622376 -335.178908) (xy 89.622376 -334.929226)
					(xy 87.46998 -334.929226)
				)
			)
		)
	)
)
